# T6G (Grand Teton) — schematic netlist excerpt (pin names and nets, part order shuffled) for the footprints in the layout excerpt that follows; sources: Cadence DE-HDL packaged netlist, KiCad conversion of 04192023_DAF0TMB3IC0_F0TG_MB_C_brd_V02_OCP.brd

C2436  Q_CAP  22UF 4V 20% X6S  pkg C0402  page 74 : A = PVDDCR_SOC_P1 ; B = GND
PC159_6  Q_CAP  22UF 16V 20% X6S  pkg C0805  page 196 : A = SW_P12V_AUX_PVDDCR_CPU0_P0_FLT ; B = GND
R33  Q_RES  4.7K 1% EMPTY  pkg 0402LF  page 131 : A = P3V3_OCP_SFF ; B = OCP_SFF_ID1

(kicad_pcb
	(version 20260206)
	(generator "pcbnew")
	(generator_version "10.0")
	(general
		(thickness 1.6)
		(legacy_teardrops no)
	)
	(paper "A4")
	(title_block
		(title "04192023_DAF0TMB3IC0_F0TG_MB_C_brd_V02_OCP.brd")
		(comment 1 "Grand Teton / footprints 5164-5166 of 8354")
	)
	(layers
		(0 "F.Cu" signal "TOP")
		(4 "In1.Cu" signal "GND")
		(6 "In2.Cu" signal "IN1")
		(8 "In3.Cu" signal "GND1")
		(10 "In4.Cu" signal "IN2")
		(12 "In5.Cu" signal "GND2")
		(14 "In6.Cu" signal "IN3")
		(16 "In7.Cu" signal "GND3")
		(18 "In8.Cu" signal "VCC")
		(20 "In9.Cu" signal "VCC1")
		(22 "In10.Cu" signal "GND4")
		(24 "In11.Cu" signal "IN4")
		(26 "In12.Cu" signal "GND5")
		(28 "In13.Cu" signal "IN5")
		(30 "In14.Cu" signal "GND6")
		(32 "In15.Cu" signal "IN6")
		(34 "In16.Cu" signal "GND7")
		(2 "B.Cu" signal "BOTTOM")
		(9 "F.Adhes" user "F.Adhesive")
		(11 "B.Adhes" user "B.Adhesive")
		(13 "F.Paste" user "Package Geometry/Pastemask Top")
		(15 "B.Paste" user "Package Geometry/Pastemask Bottom")
		(5 "F.SilkS" user "Ref Des/Silkscreen Top")
		(7 "B.SilkS" user "Ref Des/Silkscreen Bottom")
		(1 "F.Mask" user "Board Geometry/Soldermask Top")
		(3 "B.Mask" user "Board Geometry/Soldermask Bottom")
		(17 "Dwgs.User" user "User.Drawings")
		(19 "Cmts.User" user "User.Comments")
		(21 "Eco1.User" user "User.Eco1")
		(23 "Eco2.User" user "User.Eco2")
		(25 "Edge.Cuts" user "Board Geometry/Outline")
		(27 "Margin" user)
		(31 "F.CrtYd" user "Package Geometry/Place Bound Top")
		(29 "B.CrtYd" user "Package Geometry/Place Bound Bottom")
		(35 "F.Fab" user "Ref Des/Assembly Top")
		(33 "B.Fab" user "Ref Des/Assembly Bottom")
	)
	(footprint ""
		(layer "B.Cu")
		(at 450.534278 -8.3566 90)
		(property "Reference" "R33"
			(at 0 0 90)
			(layer "B.SilkS")
			(hide yes)
			(effects
				(font
					(size 1.27 1.27)
				)
				(justify mirror)
			)
		)
		(property "Value" ""
			(at 0 0 90)
			(layer "B.Fab")
			(effects
				(font
					(size 1.27 1.27)
				)
				(justify mirror)
			)
		)
		(duplicate_pad_numbers_are_jumpers no)
		(fp_line
			(start 0.7874 -0.4064)
			(end -0.7874 -0.4064)
			(stroke
				(width 0.1524)
				(type default)
			)
			(layer "B.SilkS")
		)
		(fp_line
			(start -0.7874 -0.4064)
			(end -0.7874 0.4064)
			(stroke
				(width 0.1524)
				(type default)
			)
			(layer "B.SilkS")
		)
		(fp_line
			(start 0.7874 0.4064)
			(end 0.7874 -0.4064)
			(stroke
				(width 0.1524)
				(type default)
			)
			(layer "B.SilkS")
		)
		(fp_line
			(start -0.7874 0.4064)
			(end 0.7874 0.4064)
			(stroke
				(width 0.1524)
				(type default)
			)
			(layer "B.SilkS")
		)
		(fp_line
			(start 0.67945 -0.305054)
			(end 0.12065 -0.305054)
			(stroke
				(width 0.1)
				(type default)
			)
			(layer "B.Fab")
		)
		(fp_line
			(start 0.12065 -0.305054)
			(end 0.12065 -0.2794)
			(stroke
				(width 0.1)
				(type default)
			)
			(layer "B.Fab")
		)
		(fp_line
			(start -0.12065 -0.3048)
			(end -0.67945 -0.3048)
			(stroke
				(width 0.1)
				(type default)
			)
			(layer "B.Fab")
		)
		(fp_line
			(start -0.67945 -0.3048)
			(end -0.67945 0.3048)
			(stroke
				(width 0.1)
				(type default)
			)
			(layer "B.Fab")
		)
		(fp_line
			(start 0.12065 -0.2794)
			(end -0.12065 -0.2794)
			(stroke
				(width 0.1)
				(type default)
			)
			(layer "B.Fab")
		)
		(fp_line
			(start -0.12065 -0.2794)
			(end -0.12065 -0.3048)
			(stroke
				(width 0.1)
				(type default)
			)
			(layer "B.Fab")
		)
		(fp_line
			(start 0.12065 0.2794)
			(end 0.12065 0.3048)
			(stroke
				(width 0.1)
				(type default)
			)
			(layer "B.Fab")
		)
		(fp_line
			(start -0.120396 0.2794)
			(end 0.12065 0.2794)
			(stroke
				(width 0.1)
				(type default)
			)
			(layer "B.Fab")
		)
		(fp_line
			(start 0.67945 0.3048)
			(end 0.67945 -0.305054)
			(stroke
				(width 0.1)
				(type default)
			)
			(layer "B.Fab")
		)
		(fp_line
			(start 0.12065 0.3048)
			(end 0.67945 0.3048)
			(stroke
				(width 0.1)
				(type default)
			)
			(layer "B.Fab")
		)
		(fp_line
			(start -0.120396 0.3048)
			(end -0.120396 0.2794)
			(stroke
				(width 0.1)
				(type default)
			)
			(layer "B.Fab")
		)
		(fp_line
			(start -0.67945 0.3048)
			(end -0.120396 0.3048)
			(stroke
				(width 0.1)
				(type default)
			)
			(layer "B.Fab")
		)
		(pad "1" smd circle
			(at 0.40005 0 270)
			(size 0 0)
			(layers "B.Cu" "B.Mask" "B.Paste")
			(net "P3V3_OCP_SFF")
		)
		(pad "2" smd circle
			(at -0.40005 0 270)
			(size 0 0)
			(layers "B.Cu" "B.Mask" "B.Paste")
			(net "OCP_SFF_ID1")
		)
	)
	(footprint ""
		(layer "B.Cu")
		(at 344.668856 -161.263076 -90)
		(property "Reference" "PC159_6"
			(at 0 0 90)
			(layer "B.SilkS")
			(hide yes)
			(effects
				(font
					(size 1.27 1.27)
				)
				(justify mirror)
			)
		)
		(property "Value" ""
			(at 0 0 90)
			(layer "B.Fab")
			(effects
				(font
					(size 1.27 1.27)
				)
				(justify mirror)
			)
		)
		(duplicate_pad_numbers_are_jumpers no)
		(fp_line
			(start -1.524 0.762)
			(end 1.524 0.762)
			(stroke
				(width 0.1524)
				(type default)
			)
			(layer "B.SilkS")
		)
		(fp_line
			(start 1.524 0.762)
			(end 1.524 -0.762)
			(stroke
				(width 0.1524)
				(type default)
			)
			(layer "B.SilkS")
		)
		(fp_line
			(start -1.524 -0.762)
			(end -1.524 0.762)
			(stroke
				(width 0.1524)
				(type default)
			)
			(layer "B.SilkS")
		)
		(fp_line
			(start 1.524 -0.762)
			(end -1.524 -0.762)
			(stroke
				(width 0.1524)
				(type default)
			)
			(layer "B.SilkS")
		)
		(fp_line
			(start -1.1049 0.724916)
			(end -1.1049 -0.724916)
			(stroke
				(width 0.1)
				(type default)
			)
			(layer "B.Fab")
		)
		(fp_line
			(start 1.1049 0.724916)
			(end -1.1049 0.724916)
			(stroke
				(width 0.1)
				(type default)
			)
			(layer "B.Fab")
		)
		(fp_line
			(start -1.1049 -0.724916)
			(end 1.1049 -0.724916)
			(stroke
				(width 0.1)
				(type default)
			)
			(layer "B.Fab")
		)
		(fp_line
			(start 1.1049 -0.724916)
			(end 1.1049 0.724916)
			(stroke
				(width 0.1)
				(type default)
			)
			(layer "B.Fab")
		)
		(pad "1" smd rect
			(at 0.889 0 270)
			(size 1.016 1.27)
			(layers "B.Cu" "B.Mask" "B.Paste")
			(net "SW_P12V_AUX_PVDDCR_CPU0_P0_FLT")
		)
		(pad "2" smd rect
			(at -0.889 0 270)
			(size 1.016 1.27)
			(layers "B.Cu" "B.Mask" "B.Paste")
			(net "GND")
		)
	)
	(footprint ""
		(layer "B.Cu")
		(at 106.212386 -253.432564)
		(property "Reference" "C2436"
			(at 0 0 0)
			(layer "B.SilkS")
			(hide yes)
			(effects
				(font
					(size 1.27 1.27)
				)
				(justify mirror)
			)
		)
		(property "Value" ""
			(at 0 0 0)
			(layer "B.Fab")
			(effects
				(font
					(size 1.27 1.27)
				)
				(justify mirror)
			)
		)
		(duplicate_pad_numbers_are_jumpers no)
		(fp_line
			(start -0.7874 -0.4064)
			(end -0.7874 0.4064)
			(stroke
				(width 0.1524)
				(type default)
			)
			(layer "B.SilkS")
		)
		(fp_line
			(start -0.7874 0.4064)
			(end 0.7874 0.4064)
			(stroke
				(width 0.1524)
				(type default)
			)
			(layer "B.SilkS")
		)
		(fp_line
			(start 0.7874 -0.4064)
			(end -0.7874 -0.4064)
			(stroke
				(width 0.1524)
				(type default)
			)
			(layer "B.SilkS")
		)
		(fp_line
			(start 0.7874 0.4064)
			(end 0.7874 -0.4064)
			(stroke
				(width 0.1524)
				(type default)
			)
			(layer "B.SilkS")
		)
		(fp_line
			(start -0.67945 -0.3048)
			(end -0.67945 0.3048)
			(stroke
				(width 0.1)
				(type default)
			)
			(layer "B.Fab")
		)
		(fp_line
			(start -0.67945 0.3048)
			(end -0.120396 0.3048)
			(stroke
				(width 0.1)
				(type default)
			)
			(layer "B.Fab")
		)
		(fp_line
			(start -0.12065 -0.3048)
			(end -0.67945 -0.3048)
			(stroke
				(width 0.1)
				(type default)
			)
			(layer "B.Fab")
		)
		(fp_line
			(start -0.12065 -0.2794)
			(end -0.12065 -0.3048)
			(stroke
				(width 0.1)
				(type default)
			)
			(layer "B.Fab")
		)
		(fp_line
			(start -0.120396 0.2794)
			(end 0.12065 0.2794)
			(stroke
				(width 0.1)
				(type default)
			)
			(layer "B.Fab")
		)
		(fp_line
			(start -0.120396 0.3048)
			(end -0.120396 0.2794)
			(stroke
				(width 0.1)
				(type default)
			)
			(layer "B.Fab")
		)
		(fp_line
			(start 0.12065 -0.305054)
			(end 0.12065 -0.2794)
			(stroke
				(width 0.1)
				(type default)
			)
			(layer "B.Fab")
		)
		(fp_line
			(start 0.12065 -0.2794)
			(end -0.12065 -0.2794)
			(stroke
				(width 0.1)
				(type default)
			)
			(layer "B.Fab")
		)
		(fp_line
			(start 0.12065 0.2794)
			(end 0.12065 0.3048)
			(stroke
				(width 0.1)
				(type default)
			)
			(layer "B.Fab")
		)
		(fp_line
			(start 0.12065 0.3048)
			(end 0.67945 0.3048)
			(stroke
				(width 0.1)
				(type default)
			)
			(layer "B.Fab")
		)
		(fp_line
			(start 0.67945 -0.305054)
			(end 0.12065 -0.305054)
			(stroke
				(width 0.1)
				(type default)
			)
			(layer "B.Fab")
		)
		(fp_line
			(start 0.67945 0.3048)
			(end 0.67945 -0.305054)
			(stroke
				(width 0.1)
				(type default)
			)
			(layer "B.Fab")
		)
		(pad "1" smd circle
			(at 0.40005 0 180)
			(size 0 0)
			(layers "B.Cu" "B.Mask" "B.Paste")
			(net "PVDDCR_SOC_P1")
		)
		(pad "2" smd circle
			(at -0.40005 0 180)
			(size 0 0)
			(layers "B.Cu" "B.Mask" "B.Paste")
			(net "GND")
		)
	)
)
